(kicad_pcb
	(version 20260206)
	(generator "pcbnew")
	(generator_version "10.0")
	(general
		(thickness 1.6)
		(legacy_teardrops no)
	)
	(paper "A4")
	(title_block
		(title "Bryce Canyon_F.DPB_16315-1-OCP.brd")
		(comment 1 "Bryce Canyon / footprints 210-214 of 2223")
	)
	(layers
		(0 "F.Cu" signal "TOP")
		(4 "In1.Cu" signal "L2GND")
		(6 "In2.Cu" signal "L3")
		(8 "In3.Cu" signal "L4GND")
		(10 "In4.Cu" signal "L5")
		(12 "In5.Cu" signal "L6VCC")
		(14 "In6.Cu" signal "L7VCC")
		(16 "In7.Cu" signal "L8")
		(18 "In8.Cu" signal "L9GND")
		(20 "In9.Cu" signal "L10")
		(22 "In10.Cu" signal "L11GND")
		(2 "B.Cu" signal "BOTTOM")
		(9 "F.Adhes" user "F.Adhesive")
		(11 "B.Adhes" user "B.Adhesive")
		(13 "F.Paste" user "Package Geometry/Pastemask Top")
		(15 "B.Paste" user "Package Geometry/Pastemask Bottom")
		(5 "F.SilkS" user "Ref Des/Silkscreen Top")
		(7 "B.SilkS" user "Ref Des/Silkscreen Bottom")
		(1 "F.Mask" user "Board Geometry/Soldermask Top")
		(3 "B.Mask" user "Board Geometry/Soldermask Bottom")
		(17 "Dwgs.User" user "User.Drawings")
		(19 "Cmts.User" user "User.Comments")
		(21 "Eco1.User" user "User.Eco1")
		(23 "Eco2.User" user "User.Eco2")
		(25 "Edge.Cuts" user "Board Geometry/Outline")
		(27 "Margin" user)
		(31 "F.CrtYd" user "Package Geometry/Place Bound Top")
		(29 "B.CrtYd" user "Package Geometry/Place Bound Bottom")
		(35 "F.Fab" user "Ref Des/Assembly Top")
		(33 "B.Fab" user "Ref Des/Assembly Bottom")
	)
	(footprint ""
		(layer "F.Cu")
		(at 174.0662 -285.514542 90)
		(property "Reference" "C114"
			(at 0 0 90)
			(layer "F.SilkS")
			(hide yes)
			(effects
				(font
					(size 1.27 1.27)
				)
			)
		)
		(property "Value" "SCD033U25V2KX-GP"
			(at 1.1811 -2.7051 90)
			(unlocked yes)
			(layer "F.Fab")
			(hide yes)
			(effects
				(font
					(size 1.016 1.016)
					(thickness 0.1524)
				)
			)
		)
		(property "Device Type" "C402H22"
			(at 1.1811 -4.2291 90)
			(unlocked yes)
			(layer "F.Fab")
			(hide yes)
			(effects
				(font
					(size 1.016 1.016)
					(thickness 0.1524)
				)
			)
		)
		(duplicate_pad_numbers_are_jumpers no)
		(fp_rect
			(start -0.4318 0.9525)
			(end 0.4318 -0.9525)
			(stroke
				(width 0)
				(type default)
			)
			(fill no)
			(layer "F.CrtYd")
		)
		(fp_rect
			(start -0.4318 0.9525)
			(end 0.4318 -0.9525)
			(stroke
				(width 0)
				(type default)
			)
			(fill no)
			(layer "F.Fab")
		)
		(pad "1" smd custom
			(at 0 -0.4445 90)
			(size 0.1524 0.1524)
			(layers "F.Cu" "F.Mask" "F.Paste")
			(net "P12V_A")
			(options
				(clearance outline)
				(anchor circle)
			)
			(primitives
				(gr_poly
					(pts
						(arc
							(start 0.3048 -0.2032)
							(mid 0.275042 -0.275042)
							(end 0.2032 -0.3048)
						)
						(arc
							(start -0.2032 -0.3048)
							(mid -0.275042 -0.275042)
							(end -0.3048 -0.2032)
						)
						(arc
							(start -0.3048 0.2032)
							(mid -0.275042 0.275042)
							(end -0.2032 0.3048)
						)
						(arc
							(start 0.2032 0.3048)
							(mid 0.275042 0.275042)
							(end 0.3048 0.2032)
						)
					)
					(width 0)
					(fill yes)
				)
			)
		)
		(pad "2" smd custom
			(at 0 0.4445 90)
			(size 0.1524 0.1524)
			(layers "F.Cu" "F.Mask" "F.Paste")
			(net "SW_HDD_N5")
			(options
				(clearance outline)
				(anchor circle)
			)
			(primitives
				(gr_poly
					(pts
						(arc
							(start 0.3048 -0.2032)
							(mid 0.275042 -0.275042)
							(end 0.2032 -0.3048)
						)
						(arc
							(start -0.2032 -0.3048)
							(mid -0.275042 -0.275042)
							(end -0.3048 -0.2032)
						)
						(arc
							(start -0.3048 0.2032)
							(mid -0.275042 0.275042)
							(end -0.2032 0.3048)
						)
						(arc
							(start 0.2032 0.3048)
							(mid 0.275042 0.275042)
							(end 0.3048 0.2032)
						)
					)
					(width 0)
					(fill yes)
				)
			)
		)
	)
	(footprint ""
		(layer "F.Cu")
		(at 161.997898 -292.169342 -90)
		(property "Reference" "R224"
			(at 0 0 270)
			(layer "F.SilkS")
			(hide yes)
			(effects
				(font
					(size 1.27 1.27)
				)
			)
		)
		(property "Value" "10KR2F-2-GP"
			(at 0.064008 -3.993896 270)
			(unlocked yes)
			(layer "F.Fab")
			(hide yes)
			(effects
				(font
					(size 1.016 1.016)
					(thickness 0.1524)
				)
			)
		)
		(property "Device Type" "R402H16"
			(at 0.064008 -5.517896 270)
			(unlocked yes)
			(layer "F.Fab")
			(hide yes)
			(effects
				(font
					(size 1.016 1.016)
					(thickness 0.1524)
				)
			)
		)
		(duplicate_pad_numbers_are_jumpers no)
		(fp_line
			(start -0.508 -0.9398)
			(end -0.508 0.9398)
			(stroke
				(width 0.1524)
				(type default)
			)
			(layer "F.SilkS")
		)
		(fp_line
			(start 0.508 -0.9398)
			(end -0.508 -0.9398)
			(stroke
				(width 0.1524)
				(type default)
			)
			(layer "F.SilkS")
		)
		(fp_rect
			(start -0.508 0.9398)
			(end 0.508 -0.9398)
			(stroke
				(width 0)
				(type default)
			)
			(fill no)
			(layer "F.CrtYd")
		)
		(fp_rect
			(start -0.508 0.9398)
			(end 0.508 -0.9398)
			(stroke
				(width 0)
				(type default)
			)
			(fill no)
			(layer "F.Fab")
		)
		(pad "1" smd custom
			(at 0 -0.4445 270)
			(size 0.1397 0.1397)
			(layers "F.Cu" "F.Mask" "F.Paste")
			(net "P3V3_STBY_A")
			(options
				(clearance outline)
				(anchor circle)
			)
			(primitives
				(gr_poly
					(pts
						(arc
							(start -0.1778 -0.2794)
							(mid -0.249642 -0.249642)
							(end -0.2794 -0.1778)
						)
						(arc
							(start -0.2794 0.1778)
							(mid -0.249642 0.249642)
							(end -0.1778 0.2794)
						)
						(arc
							(start 0.1778 0.2794)
							(mid 0.249642 0.249642)
							(end 0.2794 0.1778)
						)
						(arc
							(start 0.2794 -0.1778)
							(mid 0.249642 -0.249642)
							(end 0.1778 -0.2794)
						)
					)
					(width 0)
					(fill yes)
				)
			)
		)
		(pad "2" smd custom
			(at 0 0.4445 270)
			(size 0.1397 0.1397)
			(layers "F.Cu" "F.Mask" "F.Paste")
			(net "HDD_PRSNT_4")
			(options
				(clearance outline)
				(anchor circle)
			)
			(primitives
				(gr_poly
					(pts
						(arc
							(start -0.1778 -0.2794)
							(mid -0.249642 -0.249642)
							(end -0.2794 -0.1778)
						)
						(arc
							(start -0.2794 0.1778)
							(mid -0.249642 0.249642)
							(end -0.1778 0.2794)
						)
						(arc
							(start 0.1778 0.2794)
							(mid 0.249642 0.249642)
							(end 0.2794 0.1778)
						)
						(arc
							(start 0.2794 -0.1778)
							(mid 0.249642 -0.249642)
							(end 0.1778 -0.2794)
						)
					)
					(width 0)
					(fill yes)
				)
			)
		)
	)
	(footprint ""
		(layer "F.Cu")
		(at 172.72 -169.117518 -90)
		(property "Reference" "R536"
			(at 0 0 270)
			(layer "F.SilkS")
			(hide yes)
			(effects
				(font
					(size 1.27 1.27)
				)
			)
		)
		(property "Value" "300KR2F-GP"
			(at 0.064008 -3.993896 270)
			(unlocked yes)
			(layer "F.Fab")
			(hide yes)
			(effects
				(font
					(size 1.016 1.016)
					(thickness 0.1524)
				)
			)
		)
		(property "Device Type" "R402H16"
			(at 0.064008 -5.517896 270)
			(unlocked yes)
			(layer "F.Fab")
			(hide yes)
			(effects
				(font
					(size 1.016 1.016)
					(thickness 0.1524)
				)
			)
		)
		(duplicate_pad_numbers_are_jumpers no)
		(fp_line
			(start -0.508 -0.9398)
			(end -0.508 0.9398)
			(stroke
				(width 0.1524)
				(type default)
			)
			(layer "F.SilkS")
		)
		(fp_line
			(start 0.508 -0.9398)
			(end -0.508 -0.9398)
			(stroke
				(width 0.1524)
				(type default)
			)
			(layer "F.SilkS")
		)
		(fp_rect
			(start -0.508 0.9398)
			(end 0.508 -0.9398)
			(stroke
				(width 0)
				(type default)
			)
			(fill no)
			(layer "F.CrtYd")
		)
		(fp_rect
			(start -0.508 0.9398)
			(end 0.508 -0.9398)
			(stroke
				(width 0)
				(type default)
			)
			(fill no)
			(layer "F.Fab")
		)
		(pad "1" smd custom
			(at 0 -0.4445 270)
			(size 0.1397 0.1397)
			(layers "F.Cu" "F.Mask" "F.Paste")
			(net "SW_HDD_N17")
			(options
				(clearance outline)
				(anchor circle)
			)
			(primitives
				(gr_poly
					(pts
						(arc
							(start -0.1778 -0.2794)
							(mid -0.249642 -0.249642)
							(end -0.2794 -0.1778)
						)
						(arc
							(start -0.2794 0.1778)
							(mid -0.249642 0.249642)
							(end -0.1778 0.2794)
						)
						(arc
							(start 0.1778 0.2794)
							(mid 0.249642 0.249642)
							(end 0.2794 0.1778)
						)
						(arc
							(start 0.2794 -0.1778)
							(mid 0.249642 -0.249642)
							(end 0.1778 -0.2794)
						)
					)
					(width 0)
					(fill yes)
				)
			)
		)
		(pad "2" smd custom
			(at 0 0.4445 270)
			(size 0.1397 0.1397)
			(layers "F.Cu" "F.Mask" "F.Paste")
			(net "P12V_A")
			(options
				(clearance outline)
				(anchor circle)
			)
			(primitives
				(gr_poly
					(pts
						(arc
							(start -0.1778 -0.2794)
							(mid -0.249642 -0.249642)
							(end -0.2794 -0.1778)
						)
						(arc
							(start -0.2794 0.1778)
							(mid -0.249642 0.249642)
							(end -0.1778 0.2794)
						)
						(arc
							(start 0.1778 0.2794)
							(mid 0.249642 0.249642)
							(end 0.2794 0.1778)
						)
						(arc
							(start 0.2794 -0.1778)
							(mid 0.249642 -0.249642)
							(end 0.1778 -0.2794)
						)
					)
					(width 0)
					(fill yes)
				)
			)
		)
	)
	(footprint ""
		(layer "F.Cu")
		(at 395.20495 -157.585918)
		(property "Reference" "R602"
			(at 0 0 0)
			(layer "F.SilkS")
			(hide yes)
			(effects
				(font
					(size 1.27 1.27)
				)
			)
		)
		(property "Value" "4K7R2J-2-GP"
			(at 0.064008 -3.993896 0)
			(unlocked yes)
			(layer "F.Fab")
			(hide yes)
			(effects
				(font
					(size 1.016 1.016)
					(thickness 0.1524)
				)
			)
		)
		(property "Device Type" "R402H16"
			(at 0.064008 -5.517896 0)
			(unlocked yes)
			(layer "F.Fab")
			(hide yes)
			(effects
				(font
					(size 1.016 1.016)
					(thickness 0.1524)
				)
			)
		)
		(duplicate_pad_numbers_are_jumpers no)
		(fp_line
			(start -0.508 -0.9398)
			(end -0.508 0.9398)
			(stroke
				(width 0.1524)
				(type default)
			)
			(layer "F.SilkS")
		)
		(fp_line
			(start 0.508 -0.9398)
			(end -0.508 -0.9398)
			(stroke
				(width 0.1524)
				(type default)
			)
			(layer "F.SilkS")
		)
		(fp_rect
			(start -0.508 0.9398)
			(end 0.508 -0.9398)
			(stroke
				(width 0)
				(type default)
			)
			(fill no)
			(layer "F.CrtYd")
		)
		(fp_rect
			(start -0.508 0.9398)
			(end 0.508 -0.9398)
			(stroke
				(width 0)
				(type default)
			)
			(fill no)
			(layer "F.Fab")
		)
		(pad "1" smd custom
			(at 0 -0.4445)
			(size 0.1397 0.1397)
			(layers "F.Cu" "F.Mask" "F.Paste")
			(net "SW_PWR_R_HDD20")
			(options
				(clearance outline)
				(anchor circle)
			)
			(primitives
				(gr_poly
					(pts
						(arc
							(start -0.1778 -0.2794)
							(mid -0.249642 -0.249642)
							(end -0.2794 -0.1778)
						)
						(arc
							(start -0.2794 0.1778)
							(mid -0.249642 0.249642)
							(end -0.1778 0.2794)
						)
						(arc
							(start 0.1778 0.2794)
							(mid 0.249642 0.249642)
							(end 0.2794 0.1778)
						)
						(arc
							(start 0.2794 -0.1778)
							(mid 0.249642 -0.249642)
							(end 0.1778 -0.2794)
						)
					)
					(width 0)
					(fill yes)
				)
			)
		)
		(pad "2" smd custom
			(at 0 0.4445)
			(size 0.1397 0.1397)
			(layers "F.Cu" "F.Mask" "F.Paste")
			(net "GND")
			(options
				(clearance outline)
				(anchor circle)
			)
			(primitives
				(gr_poly
					(pts
						(arc
							(start -0.1778 -0.2794)
							(mid -0.249642 -0.249642)
							(end -0.2794 -0.1778)
						)
						(arc
							(start -0.2794 0.1778)
							(mid -0.249642 0.249642)
							(end -0.1778 0.2794)
						)
						(arc
							(start 0.1778 0.2794)
							(mid 0.249642 0.249642)
							(end 0.2794 0.1778)
						)
						(arc
							(start 0.2794 -0.1778)
							(mid 0.249642 -0.249642)
							(end 0.1778 -0.2794)
						)
					)
					(width 0)
					(fill yes)
				)
			)
		)
	)
	(footprint ""
		(layer "F.Cu")
		(at 222.69196 -342.573356)
		(property "Reference" "R24"
			(at 0 0 0)
			(layer "F.SilkS")
			(hide yes)
			(effects
				(font
					(size 1.27 1.27)
				)
			)
		)
		(property "Value" "4K7R2F-GP"
			(at 0.064008 -3.993896 0)
			(unlocked yes)
			(layer "F.Fab")
			(hide yes)
			(effects
				(font
					(size 1.016 1.016)
					(thickness 0.1524)
				)
			)
		)
		(property "Device Type" "R402H16"
			(at 0.064008 -5.517896 0)
			(unlocked yes)
			(layer "F.Fab")
			(hide yes)
			(effects
				(font
					(size 1.016 1.016)
					(thickness 0.1524)
				)
			)
		)
		(duplicate_pad_numbers_are_jumpers no)
		(fp_line
			(start -0.508 -0.9398)
			(end -0.508 0.9398)
			(stroke
				(width 0.1524)
				(type default)
			)
			(layer "F.SilkS")
		)
		(fp_line
			(start 0.508 -0.9398)
			(end -0.508 -0.9398)
			(stroke
				(width 0.1524)
				(type default)
			)
			(layer "F.SilkS")
		)
		(fp_rect
			(start -0.508 0.9398)
			(end 0.508 -0.9398)
			(stroke
				(width 0)
				(type default)
			)
			(fill no)
			(layer "F.CrtYd")
		)
		(fp_rect
			(start -0.508 0.9398)
			(end 0.508 -0.9398)
			(stroke
				(width 0)
				(type default)
			)
			(fill no)
			(layer "F.Fab")
		)
		(pad "1" smd custom
			(at 0 -0.4445)
			(size 0.1397 0.1397)
			(layers "F.Cu" "F.Mask" "F.Paste")
			(net "P3V3_STBY_A")
			(options
				(clearance outline)
				(anchor circle)
			)
			(primitives
				(gr_poly
					(pts
						(arc
							(start -0.1778 -0.2794)
							(mid -0.249642 -0.249642)
							(end -0.2794 -0.1778)
						)
						(arc
							(start -0.2794 0.1778)
							(mid -0.249642 0.249642)
							(end -0.1778 0.2794)
						)
						(arc
							(start 0.1778 0.2794)
							(mid 0.249642 0.249642)
							(end 0.2794 0.1778)
						)
						(arc
							(start 0.2794 -0.1778)
							(mid 0.249642 -0.249642)
							(end 0.1778 -0.2794)
						)
					)
					(width 0)
					(fill yes)
				)
			)
		)
		(pad "2" smd custom
			(at 0 0.4445)
			(size 0.1397 0.1397)
			(layers "F.Cu" "F.Mask" "F.Paste")
			(net "VOL_SEN_ADDR1")
			(options
				(clearance outline)
				(anchor circle)
			)
			(primitives
				(gr_poly
					(pts
						(arc
							(start -0.1778 -0.2794)
							(mid -0.249642 -0.249642)
							(end -0.2794 -0.1778)
						)
						(arc
							(start -0.2794 0.1778)
							(mid -0.249642 0.249642)
							(end -0.1778 0.2794)
						)
						(arc
							(start 0.1778 0.2794)
							(mid 0.249642 0.249642)
							(end 0.2794 0.1778)
						)
						(arc
							(start 0.2794 -0.1778)
							(mid 0.249642 -0.249642)
							(end 0.1778 -0.2794)
						)
					)
					(width 0)
					(fill yes)
				)
			)
		)
	)
)
